(kicad_pcb
	(version 20260206)
	(generator "pcbnew")
	(generator_version "10.0")
	(general
		(thickness 1.6)
		(legacy_teardrops no)
	)
	(paper "A4")
	(title_block
		(title "12092022_DA0F0TFB6D0_F0T_FAN_BOARD_MP5048_D_brd_v02_OCP.brd")
		(comment 1 "Grand Teton / footprints 21-24 of 924")
	)
	(layers
		(0 "F.Cu" signal "TOP")
		(4 "In1.Cu" signal "GND")
		(6 "In2.Cu" signal "IN1")
		(8 "In3.Cu" signal "IN2")
		(10 "In4.Cu" signal "GND1")
		(2 "B.Cu" signal "BOTTOM")
		(9 "F.Adhes" user "F.Adhesive")
		(11 "B.Adhes" user "B.Adhesive")
		(13 "F.Paste" user "Package Geometry/Pastemask Top")
		(15 "B.Paste" user "Package Geometry/Pastemask Bottom")
		(5 "F.SilkS" user "Ref Des/Silkscreen Top")
		(7 "B.SilkS" user "Ref Des/Silkscreen Bottom")
		(1 "F.Mask" user "Board Geometry/Soldermask Top")
		(3 "B.Mask" user "Board Geometry/Soldermask Bottom")
		(17 "Dwgs.User" user "User.Drawings")
		(19 "Cmts.User" user "User.Comments")
		(21 "Eco1.User" user "User.Eco1")
		(23 "Eco2.User" user "User.Eco2")
		(25 "Edge.Cuts" user "Board Geometry/Outline")
		(27 "Margin" user)
		(31 "F.CrtYd" user "Package Geometry/Place Bound Top")
		(29 "B.CrtYd" user "Package Geometry/Place Bound Bottom")
		(35 "F.Fab" user "Ref Des/Assembly Top")
		(33 "B.Fab" user "Ref Des/Assembly Bottom")
	)
	(footprint ""
		(layer "F.Cu")
		(at 8.509 -131.191 90)
		(property "Reference" "U404"
			(at -4.21513 -1.81356 0)
			(unlocked yes)
			(layer "F.SilkS")
			(effects
				(font
					(size 0.7874 0.5842)
					(thickness 0.1524)
				)
				(justify left)
			)
		)
		(property "Value" ""
			(at 0 0 90)
			(layer "F.Fab")
			(effects
				(font
					(size 1.27 1.27)
				)
			)
		)
		(duplicate_pad_numbers_are_jumpers no)
		(fp_line
			(start 0.762 -3.6576)
			(end 0.762 -2.6416)
			(stroke
				(width 0.1524)
				(type default)
			)
			(layer "F.SilkS")
		)
		(fp_line
			(start 1.999996 -1.999996)
			(end 1.999996 -1.524)
			(stroke
				(width 0.1524)
				(type default)
			)
			(layer "F.SilkS")
		)
		(fp_line
			(start 1.524 -1.999996)
			(end 1.999996 -1.999996)
			(stroke
				(width 0.1524)
				(type default)
			)
			(layer "F.SilkS")
		)
		(fp_line
			(start -1.999996 -1.999996)
			(end -1.524 -1.999996)
			(stroke
				(width 0.1524)
				(type default)
			)
			(layer "F.SilkS")
		)
		(fp_line
			(start -1.999996 -1.524)
			(end -1.999996 -1.999996)
			(stroke
				(width 0.1524)
				(type default)
			)
			(layer "F.SilkS")
		)
		(fp_line
			(start 3.1496 0.254)
			(end 2.6416 0.254)
			(stroke
				(width 0.1524)
				(type default)
			)
			(layer "F.SilkS")
		)
		(fp_line
			(start -2.6416 0.762)
			(end -3.1496 0.762)
			(stroke
				(width 0.1524)
				(type default)
			)
			(layer "F.SilkS")
		)
		(fp_line
			(start 1.999996 1.524)
			(end 1.999996 1.999996)
			(stroke
				(width 0.1524)
				(type default)
			)
			(layer "F.SilkS")
		)
		(fp_line
			(start 1.999996 1.999996)
			(end 1.524 1.999996)
			(stroke
				(width 0.1524)
				(type default)
			)
			(layer "F.SilkS")
		)
		(fp_line
			(start -1.524 1.999996)
			(end -1.999996 1.999996)
			(stroke
				(width 0.1524)
				(type default)
			)
			(layer "F.SilkS")
		)
		(fp_line
			(start -1.999996 1.999996)
			(end -1.999996 1.524)
			(stroke
				(width 0.1524)
				(type default)
			)
			(layer "F.SilkS")
		)
		(fp_line
			(start 0.254 2.6416)
			(end 0.254 3.6576)
			(stroke
				(width 0.1524)
				(type default)
			)
			(layer "F.SilkS")
		)
		(fp_poly
			(pts
				(xy -2.63779 -1.249934) (xy -3.40741 -0.865378) (xy -3.40741 -1.634744)
			)
			(stroke
				(width 0)
				(type default)
			)
			(fill yes)
			(layer "F.SilkS")
		)
		(fp_line
			(start 0.762 -3.6576)
			(end 0.762 -2.6416)
			(stroke
				(width 0.1)
				(type default)
			)
			(layer "F.Fab")
		)
		(fp_line
			(start 1.999996 -1.999996)
			(end 1.999996 1.999996)
			(stroke
				(width 0.1)
				(type default)
			)
			(layer "F.Fab")
		)
		(fp_line
			(start -1.999996 -1.999996)
			(end 1.999996 -1.999996)
			(stroke
				(width 0.1)
				(type default)
			)
			(layer "F.Fab")
		)
		(fp_line
			(start 3.1496 0.254)
			(end 2.6416 0.254)
			(stroke
				(width 0.1)
				(type default)
			)
			(layer "F.Fab")
		)
		(fp_line
			(start -2.6416 0.762)
			(end -3.1496 0.762)
			(stroke
				(width 0.1)
				(type default)
			)
			(layer "F.Fab")
		)
		(fp_line
			(start 1.999996 1.999996)
			(end -1.999996 1.999996)
			(stroke
				(width 0.1)
				(type default)
			)
			(layer "F.Fab")
		)
		(fp_line
			(start -1.999996 1.999996)
			(end -1.999996 -1.999996)
			(stroke
				(width 0.1)
				(type default)
			)
			(layer "F.Fab")
		)
		(fp_line
			(start 0.254 2.6416)
			(end 0.254 3.6576)
			(stroke
				(width 0.1)
				(type default)
			)
			(layer "F.Fab")
		)
		(fp_poly
			(pts
				(xy -2.63779 -1.249934) (xy -3.40741 -0.865378) (xy -3.40741 -1.634744)
			)
			(stroke
				(width 0)
				(type default)
			)
			(fill yes)
			(layer "F.Fab")
		)
		(fp_text user "19"
			(at 1.41732 -3.19913 90)
			(unlocked yes)
			(layer "F.SilkS")
			(effects
				(font
					(size 0.635 0.4064)
					(thickness 0.1524)
				)
			)
		)
		(fp_text user "24"
			(at -1.52908 -3.06959 90)
			(unlocked yes)
			(layer "F.SilkS")
			(effects
				(font
					(size 0.635 0.4064)
					(thickness 0.1524)
				)
			)
		)
		(fp_text user "18"
			(at 2.55651 -1.99644 0)
			(unlocked yes)
			(layer "F.SilkS")
			(effects
				(font
					(size 0.635 0.4064)
					(thickness 0.1524)
				)
			)
		)
		(fp_text user "13"
			(at 3.01625 1.524 0)
			(unlocked yes)
			(layer "F.SilkS")
			(effects
				(font
					(size 0.635 0.4064)
					(thickness 0.1524)
				)
			)
		)
		(fp_text user "6"
			(at -3.00355 1.5494 0)
			(unlocked yes)
			(layer "F.SilkS")
			(effects
				(font
					(size 0.635 0.4064)
					(thickness 0.1524)
				)
			)
		)
		(fp_text user "12"
			(at 1.5748 3.02895 90)
			(unlocked yes)
			(layer "F.SilkS")
			(effects
				(font
					(size 0.635 0.4064)
					(thickness 0.1524)
				)
			)
		)
		(fp_text user "7"
			(at -1.67132 3.11785 90)
			(unlocked yes)
			(layer "F.SilkS")
			(effects
				(font
					(size 0.635 0.4064)
					(thickness 0.1524)
				)
			)
		)
		(fp_text user "19"
			(at 1.7018 -3.09245 90)
			(unlocked yes)
			(layer "F.Fab")
			(effects
				(font
					(size 0.635 0.4064)
					(thickness 0.1524)
				)
			)
		)
		(fp_text user "24"
			(at -1.6256 -3.01625 90)
			(unlocked yes)
			(layer "F.Fab")
			(effects
				(font
					(size 0.635 0.4064)
					(thickness 0.1524)
				)
			)
		)
		(fp_text user "18"
			(at 3.04165 -1.6256 0)
			(unlocked yes)
			(layer "F.Fab")
			(effects
				(font
					(size 0.635 0.4064)
					(thickness 0.1524)
				)
			)
		)
		(fp_text user "13"
			(at 3.01625 1.524 0)
			(unlocked yes)
			(layer "F.Fab")
			(effects
				(font
					(size 0.635 0.4064)
					(thickness 0.1524)
				)
			)
		)
		(fp_text user "6"
			(at -3.00355 1.5494 0)
			(unlocked yes)
			(layer "F.Fab")
			(effects
				(font
					(size 0.635 0.4064)
					(thickness 0.1524)
				)
			)
		)
		(fp_text user "12"
			(at 1.5748 3.02895 90)
			(unlocked yes)
			(layer "F.Fab")
			(effects
				(font
					(size 0.635 0.4064)
					(thickness 0.1524)
				)
			)
		)
		(fp_text user "7"
			(at -1.27 3.10515 90)
			(unlocked yes)
			(layer "F.Fab")
			(effects
				(font
					(size 0.635 0.4064)
					(thickness 0.1524)
				)
			)
		)
		(pad "1" smd rect
			(at -2.050034 -1.249934)
			(size 0.2794 0.9144)
			(layers "F.Cu" "F.Mask" "F.Paste")
			(net "FAN_4_PWM_R2")
		)
		(pad "2" smd rect
			(at -2.050034 -0.750062)
			(size 0.2794 0.9144)
			(layers "F.Cu" "F.Mask" "F.Paste")
			(net "FAN_4_TACH_IL_R2")
		)
		(pad "3" smd rect
			(at -2.050034 -0.249936)
			(size 0.2794 0.9144)
			(layers "F.Cu" "F.Mask" "F.Paste")
			(net "FAN_5_TACH_IL_R2")
		)
		(pad "4" smd rect
			(at -2.050034 0.249936)
			(size 0.2794 0.9144)
			(layers "F.Cu" "F.Mask" "F.Paste")
			(net "FAN_4_TACH_OL_R2")
		)
		(pad "5" smd rect
			(at -2.050034 0.750062)
			(size 0.2794 0.9144)
			(layers "F.Cu" "F.Mask" "F.Paste")
			(net "FAN_5_PWM_R2")
		)
		(pad "6" smd rect
			(at -2.050034 1.249934)
			(size 0.2794 0.9144)
			(layers "F.Cu" "F.Mask" "F.Paste")
			(net "FAN_5_TACH_OL_R2")
		)
		(pad "7" smd rect
			(at -1.249934 2.050034 90)
			(size 0.2794 0.9144)
			(layers "F.Cu" "F.Mask" "F.Paste")
			(net "FAN_6_PWM_R2")
		)
		(pad "8" smd rect
			(at -0.750062 2.050034 90)
			(size 0.2794 0.9144)
			(layers "F.Cu" "F.Mask" "F.Paste")
			(net "FAN_6_TACH_IL_R2")
		)
		(pad "9" smd rect
			(at -0.249936 2.050034 90)
			(size 0.2794 0.9144)
			(layers "F.Cu" "F.Mask" "F.Paste")
			(net "GND")
		)
		(pad "10" smd rect
			(at 0.249936 2.050034 90)
			(size 0.2794 0.9144)
			(layers "F.Cu" "F.Mask" "F.Paste")
			(net "FAN_7_TACH_IL_R2")
		)
		(pad "11" smd rect
			(at 0.750062 2.050034 90)
			(size 0.2794 0.9144)
			(layers "F.Cu" "F.Mask" "F.Paste")
			(net "FAN_6_TACH_OL_R2")
		)
		(pad "12" smd rect
			(at 1.249934 2.050034 90)
			(size 0.2794 0.9144)
			(layers "F.Cu" "F.Mask" "F.Paste")
			(net "FAN_7_PWM_R2")
		)
		(pad "13" smd rect
			(at 2.050034 1.249934)
			(size 0.2794 0.9144)
			(layers "F.Cu" "F.Mask" "F.Paste")
			(net "FAN_7_TACH_OL_R2")
		)
		(pad "14" smd rect
			(at 2.050034 0.750062)
			(size 0.2794 0.9144)
			(layers "F.Cu" "F.Mask" "F.Paste")
			(net "NC_U404_P14")
		)
		(pad "15" smd rect
			(at 2.050034 0.249936)
			(size 0.2794 0.9144)
			(layers "F.Cu" "F.Mask" "F.Paste")
			(net "NC_U404_P15")
		)
		(pad "16" smd rect
			(at 2.050034 -0.249936)
			(size 0.2794 0.9144)
			(layers "F.Cu" "F.Mask" "F.Paste")
			(net "NC_U404_P16")
		)
		(pad "17" smd rect
			(at 2.050034 -0.750062)
			(size 0.2794 0.9144)
			(layers "F.Cu" "F.Mask" "F.Paste")
			(net "NC_U404_P17")
		)
		(pad "18" smd rect
			(at 2.050034 -1.249934)
			(size 0.2794 0.9144)
			(layers "F.Cu" "F.Mask" "F.Paste")
			(net "U404_ADD0")
		)
		(pad "19" smd rect
			(at 1.249934 -2.050034 90)
			(size 0.2794 0.9144)
			(layers "F.Cu" "F.Mask" "F.Paste")
			(net "SMB_PDBV_FAN_R_U404_SCL")
		)
		(pad "20" smd rect
			(at 0.750062 -2.050034 90)
			(size 0.2794 0.9144)
			(layers "F.Cu" "F.Mask" "F.Paste")
			(net "SMB_PDBV_FAN_R_U404_SDA")
		)
		(pad "21" smd rect
			(at 0.249936 -2.050034 90)
			(size 0.2794 0.9144)
			(layers "F.Cu" "F.Mask" "F.Paste")
			(net "P3V3_AUX")
		)
		(pad "22" smd rect
			(at -0.249936 -2.050034 90)
			(size 0.2794 0.9144)
			(layers "F.Cu" "F.Mask" "F.Paste")
			(net "NC_U404_P22")
		)
		(pad "23" smd rect
			(at -0.750062 -2.050034 90)
			(size 0.2794 0.9144)
			(layers "F.Cu" "F.Mask" "F.Paste")
			(net "U404_ADD1")
		)
		(pad "24" smd rect
			(at -1.249934 -2.050034 90)
			(size 0.2794 0.9144)
			(layers "F.Cu" "F.Mask" "F.Paste")
			(net "U404_ADD2")
		)
		(pad "TH" smd rect
			(at 0 0 90)
			(size 2.7686 2.7686)
			(layers "F.Cu" "F.Mask" "F.Paste")
			(net "GND")
		)
		(zone
			(layer "F.Cu")
			(hatch none 0.5)
			(connect_pads
				(clearance 0)
			)
			(min_thickness 0.25)
			(keepout
				(tracks not_allowed)
				(vias allowed)
				(pads allowed)
				(copperpour not_allowed)
				(footprints allowed)
			)
			(placement
				(enabled no)
				(sheetname "")
			)
			(fill
				(thermal_gap 0.5)
				(thermal_bridge_width 0.5)
				(island_removal_mode 0)
			)
			(polygon
				(pts
					(xy 10.033 -129.667) (xy 6.985 -129.667) (xy 6.985 -132.715) (xy 7.0612 -132.715) (xy 7.0612 -129.7432)
					(xy 9.9568 -129.7432) (xy 9.9568 -132.6388) (xy 7.0866 -132.6388) (xy 7.0866 -132.715) (xy 10.033 -132.715)
				)
			)
		)
	)
	(footprint ""
		(layer "F.Cu")
		(at 17.399 -207.137 180)
		(property "Reference" "U364"
			(at -0.508 -1.80467 0)
			(unlocked yes)
			(layer "F.SilkS")
			(effects
				(font
					(size 0.7874 0.5842)
					(thickness 0.1524)
				)
				(justify left)
			)
		)
		(property "Value" ""
			(at 0 0 180)
			(layer "F.Fab")
			(effects
				(font
					(size 1.27 1.27)
				)
			)
		)
		(duplicate_pad_numbers_are_jumpers no)
		(fp_line
			(start 1.335278 1.100074)
			(end 1.335278 -1.100074)
			(stroke
				(width 0.1524)
				(type default)
			)
			(layer "F.SilkS")
		)
		(fp_line
			(start 1.335278 -1.100074)
			(end -1.335278 -1.100074)
			(stroke
				(width 0.1524)
				(type default)
			)
			(layer "F.SilkS")
		)
		(fp_line
			(start -1.335278 1.100074)
			(end 1.335278 1.100074)
			(stroke
				(width 0.1524)
				(type default)
			)
			(layer "F.SilkS")
		)
		(fp_line
			(start -1.335278 -1.100074)
			(end -1.335278 1.100074)
			(stroke
				(width 0.1524)
				(type default)
			)
			(layer "F.SilkS")
		)
		(fp_line
			(start 0.674878 1.100074)
			(end 0.674878 -1.100074)
			(stroke
				(width 0.1)
				(type default)
			)
			(layer "F.Fab")
		)
		(fp_line
			(start 0.674878 -1.100074)
			(end -0.674878 -1.100074)
			(stroke
				(width 0.1)
				(type default)
			)
			(layer "F.Fab")
		)
		(fp_line
			(start -0.674878 1.100074)
			(end 0.674878 1.100074)
			(stroke
				(width 0.1)
				(type default)
			)
			(layer "F.Fab")
		)
		(fp_line
			(start -0.674878 -1.100074)
			(end -0.674878 1.100074)
			(stroke
				(width 0.1)
				(type default)
			)
			(layer "F.Fab")
		)
		(pad "D" smd rect
			(at 0.8001 0 90)
			(size 0.6096 0.8128)
			(layers "F.Cu" "F.Mask" "F.Paste")
			(net "FAN_6_OK_LED_R_N")
		)
		(pad "G" smd rect
			(at -0.8001 -0.649986 90)
			(size 0.6096 0.8128)
			(layers "F.Cu" "F.Mask" "F.Paste")
			(net "FAN_6_OK_R_LED")
		)
		(pad "S" smd rect
			(at -0.8001 0.649986 90)
			(size 0.6096 0.8128)
			(layers "F.Cu" "F.Mask" "F.Paste")
			(net "GND")
		)
	)
	(footprint ""
		(layer "F.Cu")
		(at 37.465 -304.165)
		(property "Reference" "R5184"
			(at 0 0 0)
			(layer "F.SilkS")
			(hide yes)
			(effects
				(font
					(size 1.27 1.27)
				)
			)
		)
		(property "Value" ""
			(at 0 0 0)
			(layer "F.Fab")
			(effects
				(font
					(size 1.27 1.27)
				)
			)
		)
		(duplicate_pad_numbers_are_jumpers no)
		(fp_line
			(start -0.7874 -0.4064)
			(end 0.7874 -0.4064)
			(stroke
				(width 0.1524)
				(type default)
			)
			(layer "F.SilkS")
		)
		(fp_line
			(start -0.7874 0.4064)
			(end -0.7874 -0.4064)
			(stroke
				(width 0.1524)
				(type default)
			)
			(layer "F.SilkS")
		)
		(fp_line
			(start 0.7874 -0.4064)
			(end 0.7874 0.4064)
			(stroke
				(width 0.1524)
				(type default)
			)
			(layer "F.SilkS")
		)
		(fp_line
			(start 0.7874 0.4064)
			(end -0.7874 0.4064)
			(stroke
				(width 0.1524)
				(type default)
			)
			(layer "F.SilkS")
		)
		(fp_line
			(start -0.67945 -0.305054)
			(end -0.12065 -0.305054)
			(stroke
				(width 0.1)
				(type default)
			)
			(layer "F.Fab")
		)
		(fp_line
			(start -0.67945 0.3048)
			(end -0.67945 -0.305054)
			(stroke
				(width 0.1)
				(type default)
			)
			(layer "F.Fab")
		)
		(fp_line
			(start -0.12065 -0.305054)
			(end -0.12065 -0.2794)
			(stroke
				(width 0.1)
				(type default)
			)
			(layer "F.Fab")
		)
		(fp_line
			(start -0.12065 -0.2794)
			(end 0.12065 -0.2794)
			(stroke
				(width 0.1)
				(type default)
			)
			(layer "F.Fab")
		)
		(fp_line
			(start -0.12065 0.2794)
			(end -0.12065 0.3048)
			(stroke
				(width 0.1)
				(type default)
			)
			(layer "F.Fab")
		)
		(fp_line
			(start -0.12065 0.3048)
			(end -0.67945 0.3048)
			(stroke
				(width 0.1)
				(type default)
			)
			(layer "F.Fab")
		)
		(fp_line
			(start 0.120396 0.2794)
			(end -0.12065 0.2794)
			(stroke
				(width 0.1)
				(type default)
			)
			(layer "F.Fab")
		)
		(fp_line
			(start 0.120396 0.3048)
			(end 0.120396 0.2794)
			(stroke
				(width 0.1)
				(type default)
			)
			(layer "F.Fab")
		)
		(fp_line
			(start 0.12065 -0.3048)
			(end 0.67945 -0.3048)
			(stroke
				(width 0.1)
				(type default)
			)
			(layer "F.Fab")
		)
		(fp_line
			(start 0.12065 -0.2794)
			(end 0.12065 -0.3048)
			(stroke
				(width 0.1)
				(type default)
			)
			(layer "F.Fab")
		)
		(fp_line
			(start 0.67945 -0.3048)
			(end 0.67945 0.3048)
			(stroke
				(width 0.1)
				(type default)
			)
			(layer "F.Fab")
		)
		(fp_line
			(start 0.67945 0.3048)
			(end 0.120396 0.3048)
			(stroke
				(width 0.1)
				(type default)
			)
			(layer "F.Fab")
		)
		(pad "1" smd circle
			(at -0.40005 0)
			(size 0 0)
			(layers "F.Cu" "F.Mask" "F.Paste")
			(net "FAN_0_PWM_OL")
		)
		(pad "2" smd circle
			(at 0.40005 0)
			(size 0 0)
			(layers "F.Cu" "F.Mask" "F.Paste")
			(net "FAN_0_PWM_OL_R")
		)
	)
	(footprint ""
		(layer "F.Cu")
		(at 40.132 -4.445)
		(property "Reference" ""
			(at 0 0 0)
			(layer "F.SilkS")
			(hide yes)
			(effects
				(font
					(size 1.27 1.27)
				)
			)
		)
		(property "Value" ""
			(at 0 0 0)
			(layer "F.Fab")
			(effects
				(font
					(size 1.27 1.27)
				)
			)
		)
		(duplicate_pad_numbers_are_jumpers no)
		(pad "1" smd circle
			(at 0 0)
			(size 0.9906 0.9906)
			(layers "F.Cu" "F.Mask" "F.Paste")
			(net "Net_126")
		)
		(zone
			(layer "F.Cu")
			(hatch none 0.5)
			(connect_pads
				(clearance 0)
			)
			(min_thickness 0.25)
			(keepout
				(tracks not_allowed)
				(vias allowed)
				(pads allowed)
				(copperpour not_allowed)
				(footprints allowed)
			)
			(placement
				(enabled no)
				(sheetname "")
			)
			(fill
				(thermal_gap 0.5)
				(thermal_bridge_width 0.5)
				(island_removal_mode 0)
			)
			(polygon
				(pts
					(arc
						(start 41.7576 -4.445)
						(mid 38.5064 -4.445)
						(end 41.7576 -4.445)
					)
				)
			)
		)
	)
)
